# S9S_MB_2U (Grand Teton) — schematic netlist excerpt (pin names and nets, part order shuffled) for the footprints in the layout excerpt that follows; sources: Cadence DE-HDL packaged netlist, KiCad conversion of 03242023_DA0F0TMBIJ0_F0T_Motherboard_J_brd_V01_OCP.brd

C214  Q_CAP  47UF 4V 20% X6S  pkg C0805  page 74 : A = PVCCIN_CPU0 ; B = GND
R3522  Q_RES  54.9K 1% CHIP  pkg 0402LF  page 234 : A = P3V3_AUX ; B = SMB_2_BMC_GPU_BUF_R_SDA
C714  Q_CAP_DIFFBUS  DIFF BUS_0.22UF 6.3V 20% X6S  pkg C0201  page 176 : \1\ = P5E_CPU1_PE0_TX_C_DN<13> ; \2\ = P5E_CPU1_PE0_TX_DN<13>
C863  Q_CAP_DIFFBUS  DIFF BUS_0.22UF 6.3V 20% X6S  pkg C0201  page 174 : \1\ = P5E_CPU0_PE1_TX_C_DP<3> ; \2\ = P5E_CPU0_PE1_TX_DP<3>

(kicad_pcb
	(version 20260206)
	(generator "pcbnew")
	(generator_version "10.0")
	(general
		(thickness 1.6)
		(legacy_teardrops no)
	)
	(paper "A4")
	(title_block
		(title "03242023_DA0F0TMBIJ0_F0T_Motherboard_J_brd_V01_OCP.brd")
		(comment 1 "Grand Teton / footprints 1729-1732 of 6105")
	)
	(layers
		(0 "F.Cu" signal "TOP")
		(4 "In1.Cu" signal "GND")
		(6 "In2.Cu" signal "IN1")
		(8 "In3.Cu" signal "GND1")
		(10 "In4.Cu" signal "IN2")
		(12 "In5.Cu" signal "GND2")
		(14 "In6.Cu" signal "IN3")
		(16 "In7.Cu" signal "GND3")
		(18 "In8.Cu" signal "VCC")
		(20 "In9.Cu" signal "VCC1")
		(22 "In10.Cu" signal "GND4")
		(24 "In11.Cu" signal "IN4")
		(26 "In12.Cu" signal "GND5")
		(28 "In13.Cu" signal "IN5")
		(30 "In14.Cu" signal "GND6")
		(32 "In15.Cu" signal "IN6")
		(34 "In16.Cu" signal "GND7")
		(2 "B.Cu" signal "BOTTOM")
		(9 "F.Adhes" user "F.Adhesive")
		(11 "B.Adhes" user "B.Adhesive")
		(13 "F.Paste" user "Package Geometry/Pastemask Top")
		(15 "B.Paste" user "Package Geometry/Pastemask Bottom")
		(5 "F.SilkS" user "Ref Des/Silkscreen Top")
		(7 "B.SilkS" user "Ref Des/Silkscreen Bottom")
		(1 "F.Mask" user "Board Geometry/Soldermask Top")
		(3 "B.Mask" user "Board Geometry/Soldermask Bottom")
		(17 "Dwgs.User" user "User.Drawings")
		(19 "Cmts.User" user "User.Comments")
		(21 "Eco1.User" user "User.Eco1")
		(23 "Eco2.User" user "User.Eco2")
		(25 "Edge.Cuts" user "Board Geometry/Outline")
		(27 "Margin" user)
		(31 "F.CrtYd" user "Package Geometry/Place Bound Top")
		(29 "B.CrtYd" user "Package Geometry/Place Bound Bottom")
		(35 "F.Fab" user "Ref Des/Assembly Top")
		(33 "B.Fab" user "Ref Des/Assembly Bottom")
	)
	(footprint ""
		(layer "F.Cu")
		(at 54.080918 -402.371052 -90)
		(property "Reference" "C714"
			(at 0 0 270)
			(layer "F.SilkS")
			(hide yes)
			(effects
				(font
					(size 1.27 1.27)
				)
			)
		)
		(property "Value" ""
			(at 0 0 270)
			(layer "F.Fab")
			(effects
				(font
					(size 1.27 1.27)
				)
			)
		)
		(duplicate_pad_numbers_are_jumpers no)
		(fp_line
			(start -0.299974 0.150114)
			(end -0.299974 -0.150114)
			(stroke
				(width 0.1)
				(type default)
			)
			(layer "F.Fab")
		)
		(fp_line
			(start 0.299974 0.150114)
			(end -0.299974 0.150114)
			(stroke
				(width 0.1)
				(type default)
			)
			(layer "F.Fab")
		)
		(fp_line
			(start -0.299974 -0.150114)
			(end 0.299974 -0.150114)
			(stroke
				(width 0.1)
				(type default)
			)
			(layer "F.Fab")
		)
		(fp_line
			(start 0.299974 -0.150114)
			(end 0.299974 0.150114)
			(stroke
				(width 0.1)
				(type default)
			)
			(layer "F.Fab")
		)
		(pad "1" smd rect
			(at -0.2667 0 270)
			(size 0.3048 0.381)
			(layers "F.Cu" "F.Mask" "F.Paste")
			(net "P5E_CPU1_PE0_TX_C_DN<13>")
		)
		(pad "2" smd rect
			(at 0.2667 0 270)
			(size 0.3048 0.381)
			(layers "F.Cu" "F.Mask" "F.Paste")
			(net "P5E_CPU1_PE0_TX_DN<13>")
		)
	)
	(footprint ""
		(layer "F.Cu")
		(at 32.780478 -438.704228)
		(property "Reference" "R3522"
			(at 0 0 0)
			(layer "F.SilkS")
			(hide yes)
			(effects
				(font
					(size 1.27 1.27)
				)
			)
		)
		(property "Value" ""
			(at 0 0 0)
			(layer "F.Fab")
			(effects
				(font
					(size 1.27 1.27)
				)
			)
		)
		(duplicate_pad_numbers_are_jumpers no)
		(fp_line
			(start -0.7874 -0.4064)
			(end 0.7874 -0.4064)
			(stroke
				(width 0.1524)
				(type default)
			)
			(layer "F.SilkS")
		)
		(fp_line
			(start -0.7874 0.4064)
			(end -0.7874 -0.4064)
			(stroke
				(width 0.1524)
				(type default)
			)
			(layer "F.SilkS")
		)
		(fp_line
			(start 0.7874 -0.4064)
			(end 0.7874 0.4064)
			(stroke
				(width 0.1524)
				(type default)
			)
			(layer "F.SilkS")
		)
		(fp_line
			(start 0.7874 0.4064)
			(end -0.7874 0.4064)
			(stroke
				(width 0.1524)
				(type default)
			)
			(layer "F.SilkS")
		)
		(fp_line
			(start -0.67945 -0.305054)
			(end -0.12065 -0.305054)
			(stroke
				(width 0.1)
				(type default)
			)
			(layer "F.Fab")
		)
		(fp_line
			(start -0.67945 0.3048)
			(end -0.67945 -0.305054)
			(stroke
				(width 0.1)
				(type default)
			)
			(layer "F.Fab")
		)
		(fp_line
			(start -0.12065 -0.305054)
			(end -0.12065 -0.2794)
			(stroke
				(width 0.1)
				(type default)
			)
			(layer "F.Fab")
		)
		(fp_line
			(start -0.12065 -0.2794)
			(end 0.12065 -0.2794)
			(stroke
				(width 0.1)
				(type default)
			)
			(layer "F.Fab")
		)
		(fp_line
			(start -0.12065 0.2794)
			(end -0.12065 0.3048)
			(stroke
				(width 0.1)
				(type default)
			)
			(layer "F.Fab")
		)
		(fp_line
			(start -0.12065 0.3048)
			(end -0.67945 0.3048)
			(stroke
				(width 0.1)
				(type default)
			)
			(layer "F.Fab")
		)
		(fp_line
			(start 0.120396 0.2794)
			(end -0.12065 0.2794)
			(stroke
				(width 0.1)
				(type default)
			)
			(layer "F.Fab")
		)
		(fp_line
			(start 0.120396 0.3048)
			(end 0.120396 0.2794)
			(stroke
				(width 0.1)
				(type default)
			)
			(layer "F.Fab")
		)
		(fp_line
			(start 0.12065 -0.3048)
			(end 0.67945 -0.3048)
			(stroke
				(width 0.1)
				(type default)
			)
			(layer "F.Fab")
		)
		(fp_line
			(start 0.12065 -0.2794)
			(end 0.12065 -0.3048)
			(stroke
				(width 0.1)
				(type default)
			)
			(layer "F.Fab")
		)
		(fp_line
			(start 0.67945 -0.3048)
			(end 0.67945 0.3048)
			(stroke
				(width 0.1)
				(type default)
			)
			(layer "F.Fab")
		)
		(fp_line
			(start 0.67945 0.3048)
			(end 0.120396 0.3048)
			(stroke
				(width 0.1)
				(type default)
			)
			(layer "F.Fab")
		)
		(pad "1" smd circle
			(at -0.40005 0)
			(size 0 0)
			(layers "F.Cu" "F.Mask" "F.Paste")
			(net "P3V3_AUX")
		)
		(pad "2" smd circle
			(at 0.40005 0)
			(size 0 0)
			(layers "F.Cu" "F.Mask" "F.Paste")
			(net "SMB_2_BMC_GPU_BUF_R_SDA")
		)
	)
	(footprint ""
		(layer "F.Cu")
		(at 353.36988 -296.05478 180)
		(property "Reference" "C214"
			(at 0 0 180)
			(layer "F.SilkS")
			(hide yes)
			(effects
				(font
					(size 1.27 1.27)
				)
			)
		)
		(property "Value" ""
			(at 0 0 180)
			(layer "F.Fab")
			(effects
				(font
					(size 1.27 1.27)
				)
			)
		)
		(duplicate_pad_numbers_are_jumpers no)
		(fp_line
			(start 1.524 0.762)
			(end -1.524 0.762)
			(stroke
				(width 0.1524)
				(type default)
			)
			(layer "F.SilkS")
		)
		(fp_line
			(start 1.524 -0.762)
			(end 1.524 0.762)
			(stroke
				(width 0.1524)
				(type default)
			)
			(layer "F.SilkS")
		)
		(fp_line
			(start -1.524 0.762)
			(end -1.524 -0.762)
			(stroke
				(width 0.1524)
				(type default)
			)
			(layer "F.SilkS")
		)
		(fp_line
			(start -1.524 -0.762)
			(end 1.524 -0.762)
			(stroke
				(width 0.1524)
				(type default)
			)
			(layer "F.SilkS")
		)
		(fp_line
			(start 1.1049 0.724916)
			(end 1.1049 -0.724916)
			(stroke
				(width 0.1)
				(type default)
			)
			(layer "F.Fab")
		)
		(fp_line
			(start 1.1049 -0.724916)
			(end -1.1049 -0.724916)
			(stroke
				(width 0.1)
				(type default)
			)
			(layer "F.Fab")
		)
		(fp_line
			(start -1.1049 0.724916)
			(end 1.1049 0.724916)
			(stroke
				(width 0.1)
				(type default)
			)
			(layer "F.Fab")
		)
		(fp_line
			(start -1.1049 -0.724916)
			(end -1.1049 0.724916)
			(stroke
				(width 0.1)
				(type default)
			)
			(layer "F.Fab")
		)
		(pad "1" smd rect
			(at -0.889 0)
			(size 1.016 1.27)
			(layers "F.Cu" "F.Mask" "F.Paste")
			(net "PVCCIN_CPU0")
		)
		(pad "2" smd rect
			(at 0.889 0)
			(size 1.016 1.27)
			(layers "F.Cu" "F.Mask" "F.Paste")
			(net "GND")
		)
	)
	(footprint ""
		(layer "F.Cu")
		(at 423.8498 -16.088614 90)
		(property "Reference" "C863"
			(at 0 0 90)
			(layer "F.SilkS")
			(hide yes)
			(effects
				(font
					(size 1.27 1.27)
				)
			)
		)
		(property "Value" ""
			(at 0 0 90)
			(layer "F.Fab")
			(effects
				(font
					(size 1.27 1.27)
				)
			)
		)
		(duplicate_pad_numbers_are_jumpers no)
		(fp_line
			(start 0.299974 -0.150114)
			(end 0.299974 0.150114)
			(stroke
				(width 0.1)
				(type default)
			)
			(layer "F.Fab")
		)
		(fp_line
			(start -0.299974 -0.150114)
			(end 0.299974 -0.150114)
			(stroke
				(width 0.1)
				(type default)
			)
			(layer "F.Fab")
		)
		(fp_line
			(start 0.299974 0.150114)
			(end -0.299974 0.150114)
			(stroke
				(width 0.1)
				(type default)
			)
			(layer "F.Fab")
		)
		(fp_line
			(start -0.299974 0.150114)
			(end -0.299974 -0.150114)
			(stroke
				(width 0.1)
				(type default)
			)
			(layer "F.Fab")
		)
		(pad "1" smd rect
			(at -0.2667 0 90)
			(size 0.3048 0.381)
			(layers "F.Cu" "F.Mask" "F.Paste")
			(net "P5E_CPU0_PE1_TX_C_DP<3>")
		)
		(pad "2" smd rect
			(at 0.2667 0 90)
			(size 0.3048 0.381)
			(layers "F.Cu" "F.Mask" "F.Paste")
			(net "P5E_CPU0_PE1_TX_DP<3>")
		)
	)
)
